(kicad_pcb
	(version 20260206)
	(generator "pcbnew")
	(generator_version "10.0")
	(general
		(thickness 1.6)
		(legacy_teardrops no)
	)
	(paper "A4")
	(title_block
		(title "04192023_DAF0TMB3IC0_F0TG_MB_C_brd_V02_OCP.brd")
		(comment 1 "Grand Teton / footprints 2457-2462 of 8354")
	)
	(layers
		(0 "F.Cu" signal "TOP")
		(4 "In1.Cu" signal "GND")
		(6 "In2.Cu" signal "IN1")
		(8 "In3.Cu" signal "GND1")
		(10 "In4.Cu" signal "IN2")
		(12 "In5.Cu" signal "GND2")
		(14 "In6.Cu" signal "IN3")
		(16 "In7.Cu" signal "GND3")
		(18 "In8.Cu" signal "VCC")
		(20 "In9.Cu" signal "VCC1")
		(22 "In10.Cu" signal "GND4")
		(24 "In11.Cu" signal "IN4")
		(26 "In12.Cu" signal "GND5")
		(28 "In13.Cu" signal "IN5")
		(30 "In14.Cu" signal "GND6")
		(32 "In15.Cu" signal "IN6")
		(34 "In16.Cu" signal "GND7")
		(2 "B.Cu" signal "BOTTOM")
		(9 "F.Adhes" user "F.Adhesive")
		(11 "B.Adhes" user "B.Adhesive")
		(13 "F.Paste" user "Package Geometry/Pastemask Top")
		(15 "B.Paste" user "Package Geometry/Pastemask Bottom")
		(5 "F.SilkS" user "Ref Des/Silkscreen Top")
		(7 "B.SilkS" user "Ref Des/Silkscreen Bottom")
		(1 "F.Mask" user "Board Geometry/Soldermask Top")
		(3 "B.Mask" user "Board Geometry/Soldermask Bottom")
		(17 "Dwgs.User" user "User.Drawings")
		(19 "Cmts.User" user "User.Comments")
		(21 "Eco1.User" user "User.Eco1")
		(23 "Eco2.User" user "User.Eco2")
		(25 "Edge.Cuts" user "Board Geometry/Outline")
		(27 "Margin" user)
		(31 "F.CrtYd" user "Package Geometry/Place Bound Top")
		(29 "B.CrtYd" user "Package Geometry/Place Bound Bottom")
		(35 "F.Fab" user "Ref Des/Assembly Top")
		(33 "B.Fab" user "Ref Des/Assembly Bottom")
	)
	(footprint ""
		(layer "F.Cu")
		(at 218.011502 -71.126858 180)
		(property "Reference" "PR3969"
			(at 0 0 180)
			(layer "F.SilkS")
			(hide yes)
			(effects
				(font
					(size 1.27 1.27)
				)
			)
		)
		(property "Value" ""
			(at 0 0 180)
			(layer "F.Fab")
			(effects
				(font
					(size 1.27 1.27)
				)
			)
		)
		(duplicate_pad_numbers_are_jumpers no)
		(fp_line
			(start 0.7874 0.4064)
			(end -0.7874 0.4064)
			(stroke
				(width 0.1524)
				(type default)
			)
			(layer "F.SilkS")
		)
		(fp_line
			(start 0.7874 -0.4064)
			(end 0.7874 0.4064)
			(stroke
				(width 0.1524)
				(type default)
			)
			(layer "F.SilkS")
		)
		(fp_line
			(start -0.7874 0.4064)
			(end -0.7874 -0.4064)
			(stroke
				(width 0.1524)
				(type default)
			)
			(layer "F.SilkS")
		)
		(fp_line
			(start -0.7874 -0.4064)
			(end 0.7874 -0.4064)
			(stroke
				(width 0.1524)
				(type default)
			)
			(layer "F.SilkS")
		)
		(fp_line
			(start 0.67945 0.3048)
			(end 0.120396 0.3048)
			(stroke
				(width 0.1)
				(type default)
			)
			(layer "F.Fab")
		)
		(fp_line
			(start 0.67945 -0.3048)
			(end 0.67945 0.3048)
			(stroke
				(width 0.1)
				(type default)
			)
			(layer "F.Fab")
		)
		(fp_line
			(start 0.12065 -0.2794)
			(end 0.12065 -0.3048)
			(stroke
				(width 0.1)
				(type default)
			)
			(layer "F.Fab")
		)
		(fp_line
			(start 0.12065 -0.3048)
			(end 0.67945 -0.3048)
			(stroke
				(width 0.1)
				(type default)
			)
			(layer "F.Fab")
		)
		(fp_line
			(start 0.120396 0.3048)
			(end 0.120396 0.2794)
			(stroke
				(width 0.1)
				(type default)
			)
			(layer "F.Fab")
		)
		(fp_line
			(start 0.120396 0.2794)
			(end -0.12065 0.2794)
			(stroke
				(width 0.1)
				(type default)
			)
			(layer "F.Fab")
		)
		(fp_line
			(start -0.12065 0.3048)
			(end -0.67945 0.3048)
			(stroke
				(width 0.1)
				(type default)
			)
			(layer "F.Fab")
		)
		(fp_line
			(start -0.12065 0.2794)
			(end -0.12065 0.3048)
			(stroke
				(width 0.1)
				(type default)
			)
			(layer "F.Fab")
		)
		(fp_line
			(start -0.12065 -0.2794)
			(end 0.12065 -0.2794)
			(stroke
				(width 0.1)
				(type default)
			)
			(layer "F.Fab")
		)
		(fp_line
			(start -0.12065 -0.305054)
			(end -0.12065 -0.2794)
			(stroke
				(width 0.1)
				(type default)
			)
			(layer "F.Fab")
		)
		(fp_line
			(start -0.67945 0.3048)
			(end -0.67945 -0.305054)
			(stroke
				(width 0.1)
				(type default)
			)
			(layer "F.Fab")
		)
		(fp_line
			(start -0.67945 -0.305054)
			(end -0.12065 -0.305054)
			(stroke
				(width 0.1)
				(type default)
			)
			(layer "F.Fab")
		)
		(pad "1" smd circle
			(at -0.40005 0 180)
			(size 0 0)
			(layers "F.Cu" "F.Mask" "F.Paste")
			(net "P3V3_E1S_CB_0")
		)
		(pad "2" smd circle
			(at 0.40005 0 180)
			(size 0 0)
			(layers "F.Cu" "F.Mask" "F.Paste")
			(net "GND")
		)
	)
	(footprint ""
		(layer "F.Cu")
		(at 18.330418 -415.26587 180)
		(property "Reference" "PR6601"
			(at 0 0 180)
			(layer "F.SilkS")
			(hide yes)
			(effects
				(font
					(size 1.27 1.27)
				)
			)
		)
		(property "Value" ""
			(at 0 0 180)
			(layer "F.Fab")
			(effects
				(font
					(size 1.27 1.27)
				)
			)
		)
		(duplicate_pad_numbers_are_jumpers no)
		(fp_line
			(start 0.7874 0.4064)
			(end -0.7874 0.4064)
			(stroke
				(width 0.1524)
				(type default)
			)
			(layer "F.SilkS")
		)
		(fp_line
			(start 0.7874 -0.4064)
			(end 0.7874 0.4064)
			(stroke
				(width 0.1524)
				(type default)
			)
			(layer "F.SilkS")
		)
		(fp_line
			(start -0.7874 0.4064)
			(end -0.7874 -0.4064)
			(stroke
				(width 0.1524)
				(type default)
			)
			(layer "F.SilkS")
		)
		(fp_line
			(start -0.7874 -0.4064)
			(end 0.7874 -0.4064)
			(stroke
				(width 0.1524)
				(type default)
			)
			(layer "F.SilkS")
		)
		(fp_line
			(start 0.67945 0.3048)
			(end 0.120396 0.3048)
			(stroke
				(width 0.1)
				(type default)
			)
			(layer "F.Fab")
		)
		(fp_line
			(start 0.67945 -0.3048)
			(end 0.67945 0.3048)
			(stroke
				(width 0.1)
				(type default)
			)
			(layer "F.Fab")
		)
		(fp_line
			(start 0.12065 -0.2794)
			(end 0.12065 -0.3048)
			(stroke
				(width 0.1)
				(type default)
			)
			(layer "F.Fab")
		)
		(fp_line
			(start 0.12065 -0.3048)
			(end 0.67945 -0.3048)
			(stroke
				(width 0.1)
				(type default)
			)
			(layer "F.Fab")
		)
		(fp_line
			(start 0.120396 0.3048)
			(end 0.120396 0.2794)
			(stroke
				(width 0.1)
				(type default)
			)
			(layer "F.Fab")
		)
		(fp_line
			(start 0.120396 0.2794)
			(end -0.12065 0.2794)
			(stroke
				(width 0.1)
				(type default)
			)
			(layer "F.Fab")
		)
		(fp_line
			(start -0.12065 0.3048)
			(end -0.67945 0.3048)
			(stroke
				(width 0.1)
				(type default)
			)
			(layer "F.Fab")
		)
		(fp_line
			(start -0.12065 0.2794)
			(end -0.12065 0.3048)
			(stroke
				(width 0.1)
				(type default)
			)
			(layer "F.Fab")
		)
		(fp_line
			(start -0.12065 -0.2794)
			(end 0.12065 -0.2794)
			(stroke
				(width 0.1)
				(type default)
			)
			(layer "F.Fab")
		)
		(fp_line
			(start -0.12065 -0.305054)
			(end -0.12065 -0.2794)
			(stroke
				(width 0.1)
				(type default)
			)
			(layer "F.Fab")
		)
		(fp_line
			(start -0.67945 0.3048)
			(end -0.67945 -0.305054)
			(stroke
				(width 0.1)
				(type default)
			)
			(layer "F.Fab")
		)
		(fp_line
			(start -0.67945 -0.305054)
			(end -0.12065 -0.305054)
			(stroke
				(width 0.1)
				(type default)
			)
			(layer "F.Fab")
		)
		(pad "1" smd circle
			(at -0.40005 0 180)
			(size 0 0)
			(layers "F.Cu" "F.Mask" "F.Paste")
			(net "P0V9_RETIMER_CPU1_SENSE_SH_P")
		)
		(pad "2" smd circle
			(at 0.40005 0 180)
			(size 0 0)
			(layers "F.Cu" "F.Mask" "F.Paste")
			(net "P0V9_RETIMER_CPU1_SENSE_R_P")
		)
	)
	(footprint ""
		(layer "F.Cu")
		(at 38.354 -366.776 90)
		(property "Reference" "PR251"
			(at 0 0 90)
			(layer "F.SilkS")
			(hide yes)
			(effects
				(font
					(size 1.27 1.27)
				)
			)
		)
		(property "Value" ""
			(at 0 0 90)
			(layer "F.Fab")
			(effects
				(font
					(size 1.27 1.27)
				)
			)
		)
		(duplicate_pad_numbers_are_jumpers no)
		(fp_line
			(start 0.7874 -0.4064)
			(end 0.7874 0.4064)
			(stroke
				(width 0.1524)
				(type default)
			)
			(layer "F.SilkS")
		)
		(fp_line
			(start -0.7874 -0.4064)
			(end 0.7874 -0.4064)
			(stroke
				(width 0.1524)
				(type default)
			)
			(layer "F.SilkS")
		)
		(fp_line
			(start 0.7874 0.4064)
			(end -0.7874 0.4064)
			(stroke
				(width 0.1524)
				(type default)
			)
			(layer "F.SilkS")
		)
		(fp_line
			(start -0.7874 0.4064)
			(end -0.7874 -0.4064)
			(stroke
				(width 0.1524)
				(type default)
			)
			(layer "F.SilkS")
		)
		(fp_line
			(start -0.12065 -0.305054)
			(end -0.12065 -0.2794)
			(stroke
				(width 0.1)
				(type default)
			)
			(layer "F.Fab")
		)
		(fp_line
			(start -0.67945 -0.305054)
			(end -0.12065 -0.305054)
			(stroke
				(width 0.1)
				(type default)
			)
			(layer "F.Fab")
		)
		(fp_line
			(start 0.67945 -0.3048)
			(end 0.67945 0.3048)
			(stroke
				(width 0.1)
				(type default)
			)
			(layer "F.Fab")
		)
		(fp_line
			(start 0.12065 -0.3048)
			(end 0.67945 -0.3048)
			(stroke
				(width 0.1)
				(type default)
			)
			(layer "F.Fab")
		)
		(fp_line
			(start 0.12065 -0.2794)
			(end 0.12065 -0.3048)
			(stroke
				(width 0.1)
				(type default)
			)
			(layer "F.Fab")
		)
		(fp_line
			(start -0.12065 -0.2794)
			(end 0.12065 -0.2794)
			(stroke
				(width 0.1)
				(type default)
			)
			(layer "F.Fab")
		)
		(fp_line
			(start 0.120396 0.2794)
			(end -0.12065 0.2794)
			(stroke
				(width 0.1)
				(type default)
			)
			(layer "F.Fab")
		)
		(fp_line
			(start -0.12065 0.2794)
			(end -0.12065 0.3048)
			(stroke
				(width 0.1)
				(type default)
			)
			(layer "F.Fab")
		)
		(fp_line
			(start 0.67945 0.3048)
			(end 0.120396 0.3048)
			(stroke
				(width 0.1)
				(type default)
			)
			(layer "F.Fab")
		)
		(fp_line
			(start 0.120396 0.3048)
			(end 0.120396 0.2794)
			(stroke
				(width 0.1)
				(type default)
			)
			(layer "F.Fab")
		)
		(fp_line
			(start -0.12065 0.3048)
			(end -0.67945 0.3048)
			(stroke
				(width 0.1)
				(type default)
			)
			(layer "F.Fab")
		)
		(fp_line
			(start -0.67945 0.3048)
			(end -0.67945 -0.305054)
			(stroke
				(width 0.1)
				(type default)
			)
			(layer "F.Fab")
		)
		(pad "1" smd circle
			(at -0.40005 0 90)
			(size 0 0)
			(layers "F.Cu" "F.Mask" "F.Paste")
			(net "P12V_AUX")
		)
		(pad "2" smd circle
			(at 0.40005 0 90)
			(size 0 0)
			(layers "F.Cu" "F.Mask" "F.Paste")
			(net "PVDDCR_CPU1_P1_VINSEN")
		)
	)
	(footprint ""
		(layer "F.Cu")
		(at 213.41588 -50.637948 90)
		(property "Reference" "R3756"
			(at 0 0 90)
			(layer "F.SilkS")
			(hide yes)
			(effects
				(font
					(size 1.27 1.27)
				)
			)
		)
		(property "Value" ""
			(at 0 0 90)
			(layer "F.Fab")
			(effects
				(font
					(size 1.27 1.27)
				)
			)
		)
		(duplicate_pad_numbers_are_jumpers no)
		(fp_line
			(start 0.7874 -0.4064)
			(end 0.7874 0.4064)
			(stroke
				(width 0.1524)
				(type default)
			)
			(layer "F.SilkS")
		)
		(fp_line
			(start -0.7874 -0.4064)
			(end 0.7874 -0.4064)
			(stroke
				(width 0.1524)
				(type default)
			)
			(layer "F.SilkS")
		)
		(fp_line
			(start 0.7874 0.4064)
			(end -0.7874 0.4064)
			(stroke
				(width 0.1524)
				(type default)
			)
			(layer "F.SilkS")
		)
		(fp_line
			(start -0.7874 0.4064)
			(end -0.7874 -0.4064)
			(stroke
				(width 0.1524)
				(type default)
			)
			(layer "F.SilkS")
		)
		(fp_line
			(start -0.12065 -0.305054)
			(end -0.12065 -0.2794)
			(stroke
				(width 0.1)
				(type default)
			)
			(layer "F.Fab")
		)
		(fp_line
			(start -0.67945 -0.305054)
			(end -0.12065 -0.305054)
			(stroke
				(width 0.1)
				(type default)
			)
			(layer "F.Fab")
		)
		(fp_line
			(start 0.67945 -0.3048)
			(end 0.67945 0.3048)
			(stroke
				(width 0.1)
				(type default)
			)
			(layer "F.Fab")
		)
		(fp_line
			(start 0.12065 -0.3048)
			(end 0.67945 -0.3048)
			(stroke
				(width 0.1)
				(type default)
			)
			(layer "F.Fab")
		)
		(fp_line
			(start 0.12065 -0.2794)
			(end 0.12065 -0.3048)
			(stroke
				(width 0.1)
				(type default)
			)
			(layer "F.Fab")
		)
		(fp_line
			(start -0.12065 -0.2794)
			(end 0.12065 -0.2794)
			(stroke
				(width 0.1)
				(type default)
			)
			(layer "F.Fab")
		)
		(fp_line
			(start 0.120396 0.2794)
			(end -0.12065 0.2794)
			(stroke
				(width 0.1)
				(type default)
			)
			(layer "F.Fab")
		)
		(fp_line
			(start -0.12065 0.2794)
			(end -0.12065 0.3048)
			(stroke
				(width 0.1)
				(type default)
			)
			(layer "F.Fab")
		)
		(fp_line
			(start 0.67945 0.3048)
			(end 0.120396 0.3048)
			(stroke
				(width 0.1)
				(type default)
			)
			(layer "F.Fab")
		)
		(fp_line
			(start 0.120396 0.3048)
			(end 0.120396 0.2794)
			(stroke
				(width 0.1)
				(type default)
			)
			(layer "F.Fab")
		)
		(fp_line
			(start -0.12065 0.3048)
			(end -0.67945 0.3048)
			(stroke
				(width 0.1)
				(type default)
			)
			(layer "F.Fab")
		)
		(fp_line
			(start -0.67945 0.3048)
			(end -0.67945 -0.305054)
			(stroke
				(width 0.1)
				(type default)
			)
			(layer "F.Fab")
		)
		(pad "1" smd circle
			(at -0.40005 0 90)
			(size 0 0)
			(layers "F.Cu" "F.Mask" "F.Paste")
			(net "SMB_INA230_2_3V3AUX_SDA_R")
		)
		(pad "2" smd circle
			(at 0.40005 0 90)
			(size 0 0)
			(layers "F.Cu" "F.Mask" "F.Paste")
			(net "SMB_INA230_2_3V3AUX_SDA_R1")
		)
	)
	(footprint ""
		(layer "F.Cu")
		(at 419.230302 -438.234836 90)
		(property "Reference" "R2919"
			(at 0 0 90)
			(layer "F.SilkS")
			(hide yes)
			(effects
				(font
					(size 1.27 1.27)
				)
			)
		)
		(property "Value" ""
			(at 0 0 90)
			(layer "F.Fab")
			(effects
				(font
					(size 1.27 1.27)
				)
			)
		)
		(duplicate_pad_numbers_are_jumpers no)
		(fp_line
			(start 0.7874 -0.4064)
			(end 0.7874 0.4064)
			(stroke
				(width 0.1524)
				(type default)
			)
			(layer "F.SilkS")
		)
		(fp_line
			(start -0.7874 -0.4064)
			(end 0.7874 -0.4064)
			(stroke
				(width 0.1524)
				(type default)
			)
			(layer "F.SilkS")
		)
		(fp_line
			(start 0.7874 0.4064)
			(end -0.7874 0.4064)
			(stroke
				(width 0.1524)
				(type default)
			)
			(layer "F.SilkS")
		)
		(fp_line
			(start -0.7874 0.4064)
			(end -0.7874 -0.4064)
			(stroke
				(width 0.1524)
				(type default)
			)
			(layer "F.SilkS")
		)
		(fp_line
			(start -0.12065 -0.305054)
			(end -0.12065 -0.2794)
			(stroke
				(width 0.1)
				(type default)
			)
			(layer "F.Fab")
		)
		(fp_line
			(start -0.67945 -0.305054)
			(end -0.12065 -0.305054)
			(stroke
				(width 0.1)
				(type default)
			)
			(layer "F.Fab")
		)
		(fp_line
			(start 0.67945 -0.3048)
			(end 0.67945 0.3048)
			(stroke
				(width 0.1)
				(type default)
			)
			(layer "F.Fab")
		)
		(fp_line
			(start 0.12065 -0.3048)
			(end 0.67945 -0.3048)
			(stroke
				(width 0.1)
				(type default)
			)
			(layer "F.Fab")
		)
		(fp_line
			(start 0.12065 -0.2794)
			(end 0.12065 -0.3048)
			(stroke
				(width 0.1)
				(type default)
			)
			(layer "F.Fab")
		)
		(fp_line
			(start -0.12065 -0.2794)
			(end 0.12065 -0.2794)
			(stroke
				(width 0.1)
				(type default)
			)
			(layer "F.Fab")
		)
		(fp_line
			(start 0.120396 0.2794)
			(end -0.12065 0.2794)
			(stroke
				(width 0.1)
				(type default)
			)
			(layer "F.Fab")
		)
		(fp_line
			(start -0.12065 0.2794)
			(end -0.12065 0.3048)
			(stroke
				(width 0.1)
				(type default)
			)
			(layer "F.Fab")
		)
		(fp_line
			(start 0.67945 0.3048)
			(end 0.120396 0.3048)
			(stroke
				(width 0.1)
				(type default)
			)
			(layer "F.Fab")
		)
		(fp_line
			(start 0.120396 0.3048)
			(end 0.120396 0.2794)
			(stroke
				(width 0.1)
				(type default)
			)
			(layer "F.Fab")
		)
		(fp_line
			(start -0.12065 0.3048)
			(end -0.67945 0.3048)
			(stroke
				(width 0.1)
				(type default)
			)
			(layer "F.Fab")
		)
		(fp_line
			(start -0.67945 0.3048)
			(end -0.67945 -0.305054)
			(stroke
				(width 0.1)
				(type default)
			)
			(layer "F.Fab")
		)
		(pad "1" smd circle
			(at -0.40005 0 90)
			(size 0 0)
			(layers "F.Cu" "F.Mask" "F.Paste")
			(net "P3V3_AUX")
		)
		(pad "2" smd circle
			(at 0.40005 0 90)
			(size 0 0)
			(layers "F.Cu" "F.Mask" "F.Paste")
			(net "RST_BMC_FROM_SWB_ISO_N")
		)
	)
	(footprint ""
		(layer "F.Cu")
		(at 170.46956 -388.753604 180)
		(property "Reference" "R853"
			(at 0 0 180)
			(layer "F.SilkS")
			(hide yes)
			(effects
				(font
					(size 1.27 1.27)
				)
			)
		)
		(property "Value" ""
			(at 0 0 180)
			(layer "F.Fab")
			(effects
				(font
					(size 1.27 1.27)
				)
			)
		)
		(duplicate_pad_numbers_are_jumpers no)
		(fp_line
			(start 0.7874 0.4064)
			(end -0.7874 0.4064)
			(stroke
				(width 0.1524)
				(type default)
			)
			(layer "F.SilkS")
		)
		(fp_line
			(start 0.7874 -0.4064)
			(end 0.7874 0.4064)
			(stroke
				(width 0.1524)
				(type default)
			)
			(layer "F.SilkS")
		)
		(fp_line
			(start -0.7874 0.4064)
			(end -0.7874 -0.4064)
			(stroke
				(width 0.1524)
				(type default)
			)
			(layer "F.SilkS")
		)
		(fp_line
			(start -0.7874 -0.4064)
			(end 0.7874 -0.4064)
			(stroke
				(width 0.1524)
				(type default)
			)
			(layer "F.SilkS")
		)
		(fp_line
			(start 0.67945 0.3048)
			(end 0.120396 0.3048)
			(stroke
				(width 0.1)
				(type default)
			)
			(layer "F.Fab")
		)
		(fp_line
			(start 0.67945 -0.3048)
			(end 0.67945 0.3048)
			(stroke
				(width 0.1)
				(type default)
			)
			(layer "F.Fab")
		)
		(fp_line
			(start 0.12065 -0.2794)
			(end 0.12065 -0.3048)
			(stroke
				(width 0.1)
				(type default)
			)
			(layer "F.Fab")
		)
		(fp_line
			(start 0.12065 -0.3048)
			(end 0.67945 -0.3048)
			(stroke
				(width 0.1)
				(type default)
			)
			(layer "F.Fab")
		)
		(fp_line
			(start 0.120396 0.3048)
			(end 0.120396 0.2794)
			(stroke
				(width 0.1)
				(type default)
			)
			(layer "F.Fab")
		)
		(fp_line
			(start 0.120396 0.2794)
			(end -0.12065 0.2794)
			(stroke
				(width 0.1)
				(type default)
			)
			(layer "F.Fab")
		)
		(fp_line
			(start -0.12065 0.3048)
			(end -0.67945 0.3048)
			(stroke
				(width 0.1)
				(type default)
			)
			(layer "F.Fab")
		)
		(fp_line
			(start -0.12065 0.2794)
			(end -0.12065 0.3048)
			(stroke
				(width 0.1)
				(type default)
			)
			(layer "F.Fab")
		)
		(fp_line
			(start -0.12065 -0.2794)
			(end 0.12065 -0.2794)
			(stroke
				(width 0.1)
				(type default)
			)
			(layer "F.Fab")
		)
		(fp_line
			(start -0.12065 -0.305054)
			(end -0.12065 -0.2794)
			(stroke
				(width 0.1)
				(type default)
			)
			(layer "F.Fab")
		)
		(fp_line
			(start -0.67945 0.3048)
			(end -0.67945 -0.305054)
			(stroke
				(width 0.1)
				(type default)
			)
			(layer "F.Fab")
		)
		(fp_line
			(start -0.67945 -0.305054)
			(end -0.12065 -0.305054)
			(stroke
				(width 0.1)
				(type default)
			)
			(layer "F.Fab")
		)
		(pad "1" smd rect
			(at -0.40005 0)
			(size 0.4572 0.508)
			(layers "F.Cu" "F.Mask" "F.Paste")
			(net "P1V8_CPU1_RT2_1A_1D")
		)
		(pad "2" smd rect
			(at 0.40005 0)
			(size 0.4572 0.508)
			(layers "F.Cu" "F.Mask" "F.Paste")
			(net "P1V8_CPU1_RT2_1A")
		)
	)
)
